(kicad_pcb
	(version 20260206)
	(generator "pcbnew")
	(generator_version "10.0")
	(general
		(thickness 1.6)
		(legacy_teardrops no)
	)
	(paper "A4")
	(title_block
		(title "baseboard — 13948-1b.1110WZS1818.brd")
		(comment 1 "Honey Badger (Wiwynn) / footprints 434-440 of 2523")
	)
	(layers
		(0 "F.Cu" signal "TOP")
		(4 "In1.Cu" signal "L2GND")
		(6 "In2.Cu" signal "L3")
		(8 "In3.Cu" signal "L4VCC")
		(10 "In4.Cu" signal "L5VCC")
		(12 "In5.Cu" signal "L6")
		(14 "In6.Cu" signal "L7GND")
		(2 "B.Cu" signal "BOTTOM")
		(9 "F.Adhes" user "F.Adhesive")
		(11 "B.Adhes" user "B.Adhesive")
		(13 "F.Paste" user "Package Geometry/Pastemask Top")
		(15 "B.Paste" user "Package Geometry/Pastemask Bottom")
		(5 "F.SilkS" user "Ref Des/Silkscreen Top")
		(7 "B.SilkS" user "Ref Des/Silkscreen Bottom")
		(1 "F.Mask" user "Board Geometry/Soldermask Top")
		(3 "B.Mask" user "Board Geometry/Soldermask Bottom")
		(17 "Dwgs.User" user "User.Drawings")
		(19 "Cmts.User" user "User.Comments")
		(21 "Eco1.User" user "User.Eco1")
		(23 "Eco2.User" user "User.Eco2")
		(25 "Edge.Cuts" user "Board Geometry/Outline")
		(27 "Margin" user)
		(31 "F.CrtYd" user "Package Geometry/Place Bound Top")
		(29 "B.CrtYd" user "Package Geometry/Place Bound Bottom")
		(35 "F.Fab" user "Ref Des/Assembly Top")
		(33 "B.Fab" user "Ref Des/Assembly Bottom")
	)
	(footprint ""
		(layer "F.Cu")
		(at 300.482 -102.108 180)
		(property "Reference" "R590"
			(at 0 0 180)
			(layer "F.SilkS")
			(hide yes)
			(effects
				(font
					(size 1.27 1.27)
				)
			)
		)
		(property "Value" "4K7R2F-GP"
			(at 0.064008 -3.993896 180)
			(unlocked yes)
			(layer "F.Fab")
			(hide yes)
			(effects
				(font
					(size 1.016 1.016)
					(thickness 0.1524)
				)
			)
		)
		(property "Device Type" "R402H16"
			(at 0.064008 -5.517896 180)
			(unlocked yes)
			(layer "F.Fab")
			(hide yes)
			(effects
				(font
					(size 1.016 1.016)
					(thickness 0.1524)
				)
			)
		)
		(duplicate_pad_numbers_are_jumpers no)
		(fp_line
			(start 0.508 -0.9398)
			(end -0.508 -0.9398)
			(stroke
				(width 0.1524)
				(type default)
			)
			(layer "F.SilkS")
		)
		(fp_line
			(start -0.508 -0.9398)
			(end -0.508 0.9398)
			(stroke
				(width 0.1524)
				(type default)
			)
			(layer "F.SilkS")
		)
		(fp_rect
			(start -0.508 0.9398)
			(end 0.508 -0.9398)
			(stroke
				(width 0)
				(type default)
			)
			(fill no)
			(layer "F.CrtYd")
		)
		(fp_rect
			(start -0.508 0.9398)
			(end 0.508 -0.9398)
			(stroke
				(width 0)
				(type default)
			)
			(fill no)
			(layer "F.Fab")
		)
		(pad "1" smd custom
			(at 0 -0.4445 180)
			(size 0.1397 0.1397)
			(layers "F.Cu" "F.Mask" "F.Paste")
			(net "TEMP_2_A0")
			(options
				(clearance outline)
				(anchor circle)
			)
			(primitives
				(gr_poly
					(pts
						(arc
							(start -0.1778 -0.2794)
							(mid -0.249642 -0.249642)
							(end -0.2794 -0.1778)
						)
						(arc
							(start -0.2794 0.1778)
							(mid -0.249642 0.249642)
							(end -0.1778 0.2794)
						)
						(arc
							(start 0.1778 0.2794)
							(mid 0.249642 0.249642)
							(end 0.2794 0.1778)
						)
						(arc
							(start 0.2794 -0.1778)
							(mid 0.249642 -0.249642)
							(end 0.1778 -0.2794)
						)
					)
					(width 0)
					(fill yes)
				)
			)
		)
		(pad "2" smd custom
			(at 0 0.4445 180)
			(size 0.1397 0.1397)
			(layers "F.Cu" "F.Mask" "F.Paste")
			(net "GND")
			(options
				(clearance outline)
				(anchor circle)
			)
			(primitives
				(gr_poly
					(pts
						(arc
							(start -0.1778 -0.2794)
							(mid -0.249642 -0.249642)
							(end -0.2794 -0.1778)
						)
						(arc
							(start -0.2794 0.1778)
							(mid -0.249642 0.249642)
							(end -0.1778 0.2794)
						)
						(arc
							(start 0.1778 0.2794)
							(mid 0.249642 0.249642)
							(end 0.2794 0.1778)
						)
						(arc
							(start 0.2794 -0.1778)
							(mid 0.249642 -0.249642)
							(end 0.1778 -0.2794)
						)
					)
					(width 0)
					(fill yes)
				)
			)
		)
	)
	(footprint ""
		(layer "F.Cu")
		(at 95.377 -233.807)
		(property "Reference" "SR950"
			(at 0 0 0)
			(layer "F.SilkS")
			(hide yes)
			(effects
				(font
					(size 1.27 1.27)
				)
			)
		)
		(property "Value" "4K7R2F-GP"
			(at 0.064008 -3.993896 0)
			(unlocked yes)
			(layer "F.Fab")
			(hide yes)
			(effects
				(font
					(size 1.016 1.016)
					(thickness 0.1524)
				)
			)
		)
		(property "Device Type" "R402H16"
			(at 0.064008 -5.517896 0)
			(unlocked yes)
			(layer "F.Fab")
			(hide yes)
			(effects
				(font
					(size 1.016 1.016)
					(thickness 0.1524)
				)
			)
		)
		(duplicate_pad_numbers_are_jumpers no)
		(fp_line
			(start -0.508 -0.9398)
			(end -0.508 0.9398)
			(stroke
				(width 0.1524)
				(type default)
			)
			(layer "F.SilkS")
		)
		(fp_line
			(start 0.508 -0.9398)
			(end -0.508 -0.9398)
			(stroke
				(width 0.1524)
				(type default)
			)
			(layer "F.SilkS")
		)
		(fp_rect
			(start -0.508 0.9398)
			(end 0.508 -0.9398)
			(stroke
				(width 0)
				(type default)
			)
			(fill no)
			(layer "F.CrtYd")
		)
		(fp_rect
			(start -0.508 0.9398)
			(end 0.508 -0.9398)
			(stroke
				(width 0)
				(type default)
			)
			(fill no)
			(layer "F.Fab")
		)
		(pad "1" smd custom
			(at 0 -0.4445)
			(size 0.1397 0.1397)
			(layers "F.Cu" "F.Mask" "F.Paste")
			(net "SAS_FAULT_LED9")
			(options
				(clearance outline)
				(anchor circle)
			)
			(primitives
				(gr_poly
					(pts
						(arc
							(start -0.1778 -0.2794)
							(mid -0.249642 -0.249642)
							(end -0.2794 -0.1778)
						)
						(arc
							(start -0.2794 0.1778)
							(mid -0.249642 0.249642)
							(end -0.1778 0.2794)
						)
						(arc
							(start 0.1778 0.2794)
							(mid 0.249642 0.249642)
							(end 0.2794 0.1778)
						)
						(arc
							(start 0.2794 -0.1778)
							(mid 0.249642 -0.249642)
							(end 0.1778 -0.2794)
						)
					)
					(width 0)
					(fill yes)
				)
			)
		)
		(pad "2" smd custom
			(at 0 0.4445)
			(size 0.1397 0.1397)
			(layers "F.Cu" "F.Mask" "F.Paste")
			(net "P3V3_STBY")
			(options
				(clearance outline)
				(anchor circle)
			)
			(primitives
				(gr_poly
					(pts
						(arc
							(start -0.1778 -0.2794)
							(mid -0.249642 -0.249642)
							(end -0.2794 -0.1778)
						)
						(arc
							(start -0.2794 0.1778)
							(mid -0.249642 0.249642)
							(end -0.1778 0.2794)
						)
						(arc
							(start 0.1778 0.2794)
							(mid 0.249642 0.249642)
							(end 0.2794 0.1778)
						)
						(arc
							(start 0.2794 -0.1778)
							(mid 0.249642 -0.249642)
							(end 0.1778 -0.2794)
						)
					)
					(width 0)
					(fill yes)
				)
			)
		)
	)
	(footprint ""
		(layer "F.Cu")
		(at 177.854864 -38.172136 180)
		(property "Reference" "R395"
			(at 0 0 180)
			(layer "F.SilkS")
			(hide yes)
			(effects
				(font
					(size 1.27 1.27)
				)
			)
		)
		(property "Value" "150R2F-1-GP"
			(at 0.064008 -3.993896 180)
			(unlocked yes)
			(layer "F.Fab")
			(hide yes)
			(effects
				(font
					(size 1.016 1.016)
					(thickness 0.1524)
				)
			)
		)
		(property "Device Type" "R402H16"
			(at 0.064008 -5.517896 180)
			(unlocked yes)
			(layer "F.Fab")
			(hide yes)
			(effects
				(font
					(size 1.016 1.016)
					(thickness 0.1524)
				)
			)
		)
		(duplicate_pad_numbers_are_jumpers no)
		(fp_line
			(start 0.508 -0.9398)
			(end -0.508 -0.9398)
			(stroke
				(width 0.1524)
				(type default)
			)
			(layer "F.SilkS")
		)
		(fp_line
			(start -0.508 -0.9398)
			(end -0.508 0.9398)
			(stroke
				(width 0.1524)
				(type default)
			)
			(layer "F.SilkS")
		)
		(fp_rect
			(start -0.508 0.9398)
			(end 0.508 -0.9398)
			(stroke
				(width 0)
				(type default)
			)
			(fill no)
			(layer "F.CrtYd")
		)
		(fp_rect
			(start -0.508 0.9398)
			(end 0.508 -0.9398)
			(stroke
				(width 0)
				(type default)
			)
			(fill no)
			(layer "F.Fab")
		)
		(pad "1" smd custom
			(at 0 -0.4445 180)
			(size 0.1397 0.1397)
			(layers "F.Cu" "F.Mask" "F.Paste")
			(net "PHY_LOW_PWR")
			(options
				(clearance outline)
				(anchor circle)
			)
			(primitives
				(gr_poly
					(pts
						(arc
							(start -0.1778 -0.2794)
							(mid -0.249642 -0.249642)
							(end -0.2794 -0.1778)
						)
						(arc
							(start -0.2794 0.1778)
							(mid -0.249642 0.249642)
							(end -0.1778 0.2794)
						)
						(arc
							(start 0.1778 0.2794)
							(mid 0.249642 0.249642)
							(end 0.2794 0.1778)
						)
						(arc
							(start 0.2794 -0.1778)
							(mid 0.249642 -0.249642)
							(end 0.1778 -0.2794)
						)
					)
					(width 0)
					(fill yes)
				)
			)
		)
		(pad "2" smd custom
			(at 0 0.4445 180)
			(size 0.1397 0.1397)
			(layers "F.Cu" "F.Mask" "F.Paste")
			(net "GND")
			(options
				(clearance outline)
				(anchor circle)
			)
			(primitives
				(gr_poly
					(pts
						(arc
							(start -0.1778 -0.2794)
							(mid -0.249642 -0.249642)
							(end -0.2794 -0.1778)
						)
						(arc
							(start -0.2794 0.1778)
							(mid -0.249642 0.249642)
							(end -0.1778 0.2794)
						)
						(arc
							(start 0.1778 0.2794)
							(mid 0.249642 0.249642)
							(end 0.2794 0.1778)
						)
						(arc
							(start 0.2794 -0.1778)
							(mid 0.249642 -0.249642)
							(end 0.1778 -0.2794)
						)
					)
					(width 0)
					(fill yes)
				)
			)
		)
	)
	(footprint ""
		(layer "F.Cu")
		(at 184.531 -115.697 -90)
		(property "Reference" "R524"
			(at 0 0 270)
			(layer "F.SilkS")
			(hide yes)
			(effects
				(font
					(size 1.27 1.27)
				)
			)
		)
		(property "Value" "1KR2F-3-GP"
			(at 0.064008 -3.993896 270)
			(unlocked yes)
			(layer "F.Fab")
			(hide yes)
			(effects
				(font
					(size 1.016 1.016)
					(thickness 0.1524)
				)
			)
		)
		(property "Device Type" "R402H16"
			(at 0.064008 -5.517896 270)
			(unlocked yes)
			(layer "F.Fab")
			(hide yes)
			(effects
				(font
					(size 1.016 1.016)
					(thickness 0.1524)
				)
			)
		)
		(duplicate_pad_numbers_are_jumpers no)
		(fp_line
			(start -0.508 -0.9398)
			(end -0.508 0.9398)
			(stroke
				(width 0.1524)
				(type default)
			)
			(layer "F.SilkS")
		)
		(fp_line
			(start 0.508 -0.9398)
			(end -0.508 -0.9398)
			(stroke
				(width 0.1524)
				(type default)
			)
			(layer "F.SilkS")
		)
		(fp_rect
			(start -0.508 0.9398)
			(end 0.508 -0.9398)
			(stroke
				(width 0)
				(type default)
			)
			(fill no)
			(layer "F.CrtYd")
		)
		(fp_rect
			(start -0.508 0.9398)
			(end 0.508 -0.9398)
			(stroke
				(width 0)
				(type default)
			)
			(fill no)
			(layer "F.Fab")
		)
		(pad "1" smd custom
			(at 0 -0.4445 270)
			(size 0.1397 0.1397)
			(layers "F.Cu" "F.Mask" "F.Paste")
			(net "P3V3")
			(options
				(clearance outline)
				(anchor circle)
			)
			(primitives
				(gr_poly
					(pts
						(arc
							(start -0.1778 -0.2794)
							(mid -0.249642 -0.249642)
							(end -0.2794 -0.1778)
						)
						(arc
							(start -0.2794 0.1778)
							(mid -0.249642 0.249642)
							(end -0.1778 0.2794)
						)
						(arc
							(start 0.1778 0.2794)
							(mid 0.249642 0.249642)
							(end 0.2794 0.1778)
						)
						(arc
							(start 0.2794 -0.1778)
							(mid 0.249642 -0.249642)
							(end 0.1778 -0.2794)
						)
					)
					(width 0)
					(fill yes)
				)
			)
		)
		(pad "2" smd custom
			(at 0 0.4445 270)
			(size 0.1397 0.1397)
			(layers "F.Cu" "F.Mask" "F.Paste")
			(net "PMU_PLTRST_N")
			(options
				(clearance outline)
				(anchor circle)
			)
			(primitives
				(gr_poly
					(pts
						(arc
							(start -0.1778 -0.2794)
							(mid -0.249642 -0.249642)
							(end -0.2794 -0.1778)
						)
						(arc
							(start -0.2794 0.1778)
							(mid -0.249642 0.249642)
							(end -0.1778 0.2794)
						)
						(arc
							(start 0.1778 0.2794)
							(mid 0.249642 0.249642)
							(end 0.2794 0.1778)
						)
						(arc
							(start 0.2794 -0.1778)
							(mid 0.249642 -0.249642)
							(end 0.1778 -0.2794)
						)
					)
					(width 0)
					(fill yes)
				)
			)
		)
	)
	(footprint ""
		(layer "F.Cu")
		(at 144.907 -106.934 90)
		(property "Reference" "SC1164"
			(at 0 0 90)
			(layer "F.SilkS")
			(hide yes)
			(effects
				(font
					(size 1.27 1.27)
				)
			)
		)
		(property "Value" "SC100U6D3V0MX-2GP"
			(at -0.00254 -4.78536 90)
			(unlocked yes)
			(layer "F.Fab")
			(hide yes)
			(effects
				(font
					(size 1.016 1.016)
					(thickness 0.1524)
				)
			)
		)
		(property "Device Type" "C1210H107"
			(at -0.00254 -6.38048 90)
			(unlocked yes)
			(layer "F.Fab")
			(hide yes)
			(effects
				(font
					(size 1.016 1.016)
					(thickness 0.1524)
				)
			)
		)
		(duplicate_pad_numbers_are_jumpers no)
		(fp_line
			(start 1.5748 -2.3368)
			(end -1.5748 -2.3368)
			(stroke
				(width 0.1524)
				(type default)
			)
			(layer "F.SilkS")
		)
		(fp_line
			(start -1.5748 -2.3368)
			(end -1.5748 -0.762)
			(stroke
				(width 0.1524)
				(type default)
			)
			(layer "F.SilkS")
		)
		(fp_line
			(start 1.5748 -0.762)
			(end 1.5748 -2.3368)
			(stroke
				(width 0.1524)
				(type default)
			)
			(layer "F.SilkS")
		)
		(fp_line
			(start -1.5748 0.762)
			(end -1.5748 2.3368)
			(stroke
				(width 0.1524)
				(type default)
			)
			(layer "F.SilkS")
		)
		(fp_line
			(start 1.5748 2.3368)
			(end 1.5748 0.762)
			(stroke
				(width 0.1524)
				(type default)
			)
			(layer "F.SilkS")
		)
		(fp_line
			(start -1.5748 2.3368)
			(end 1.5748 2.3368)
			(stroke
				(width 0.1524)
				(type default)
			)
			(layer "F.SilkS")
		)
		(fp_rect
			(start -1.651 2.413)
			(end 1.651 -2.413)
			(stroke
				(width 0)
				(type default)
			)
			(fill no)
			(layer "F.CrtYd")
		)
		(fp_poly
			(pts
				(xy 1.651 2.413) (xy 1.651 -2.413) (xy -1.651 -2.413) (xy -1.651 2.413)
			)
			(stroke
				(width 0)
				(type default)
			)
			(fill no)
			(layer "F.Fab")
		)
		(pad "1" smd rect
			(at 0 -1.4732 90)
			(size 2.794 1.397)
			(layers "F.Cu" "F.Mask" "F.Paste")
			(net "GND")
		)
		(pad "2" smd rect
			(at 0 1.4732 90)
			(size 2.794 1.397)
			(layers "F.Cu" "F.Mask" "F.Paste")
			(net "GB_VDDA")
		)
	)
	(footprint ""
		(layer "F.Cu")
		(at 39.0652 -120.4722 -90)
		(property "Reference" "SR939"
			(at 0 0 270)
			(layer "F.SilkS")
			(hide yes)
			(effects
				(font
					(size 1.27 1.27)
				)
			)
		)
		(property "Value" "0R2J-2-GP"
			(at 0.064008 -3.993896 270)
			(unlocked yes)
			(layer "F.Fab")
			(hide yes)
			(effects
				(font
					(size 1.016 1.016)
					(thickness 0.1524)
				)
			)
		)
		(property "Device Type" "R402H16"
			(at 0.064008 -5.517896 270)
			(unlocked yes)
			(layer "F.Fab")
			(hide yes)
			(effects
				(font
					(size 1.016 1.016)
					(thickness 0.1524)
				)
			)
		)
		(duplicate_pad_numbers_are_jumpers no)
		(fp_line
			(start -0.508 -0.9398)
			(end -0.508 0.9398)
			(stroke
				(width 0.1524)
				(type default)
			)
			(layer "F.SilkS")
		)
		(fp_line
			(start 0.508 -0.9398)
			(end -0.508 -0.9398)
			(stroke
				(width 0.1524)
				(type default)
			)
			(layer "F.SilkS")
		)
		(fp_rect
			(start -0.508 0.9398)
			(end 0.508 -0.9398)
			(stroke
				(width 0)
				(type default)
			)
			(fill no)
			(layer "F.CrtYd")
		)
		(fp_rect
			(start -0.508 0.9398)
			(end 0.508 -0.9398)
			(stroke
				(width 0)
				(type default)
			)
			(fill no)
			(layer "F.Fab")
		)
		(pad "1" smd custom
			(at 0 -0.4445 270)
			(size 0.1397 0.1397)
			(layers "F.Cu" "F.Mask" "F.Paste")
			(net "SDB_TX_R")
			(options
				(clearance outline)
				(anchor circle)
			)
			(primitives
				(gr_poly
					(pts
						(arc
							(start -0.1778 -0.2794)
							(mid -0.249642 -0.249642)
							(end -0.2794 -0.1778)
						)
						(arc
							(start -0.2794 0.1778)
							(mid -0.249642 0.249642)
							(end -0.1778 0.2794)
						)
						(arc
							(start 0.1778 0.2794)
							(mid 0.249642 0.249642)
							(end 0.2794 0.1778)
						)
						(arc
							(start 0.2794 -0.1778)
							(mid 0.249642 -0.249642)
							(end 0.1778 -0.2794)
						)
					)
					(width 0)
					(fill yes)
				)
			)
		)
		(pad "2" smd custom
			(at 0 0.4445 270)
			(size 0.1397 0.1397)
			(layers "F.Cu" "F.Mask" "F.Paste")
			(net "SDB_TX")
			(options
				(clearance outline)
				(anchor circle)
			)
			(primitives
				(gr_poly
					(pts
						(arc
							(start -0.1778 -0.2794)
							(mid -0.249642 -0.249642)
							(end -0.2794 -0.1778)
						)
						(arc
							(start -0.2794 0.1778)
							(mid -0.249642 0.249642)
							(end -0.1778 0.2794)
						)
						(arc
							(start 0.1778 0.2794)
							(mid 0.249642 0.249642)
							(end 0.2794 0.1778)
						)
						(arc
							(start 0.2794 -0.1778)
							(mid 0.249642 -0.249642)
							(end 0.1778 -0.2794)
						)
					)
					(width 0)
					(fill yes)
				)
			)
		)
	)
	(footprint ""
		(layer "F.Cu")
		(at 331.343 -211.455 180)
		(property "Reference" "R200"
			(at 0 0 180)
			(layer "F.SilkS")
			(hide yes)
			(effects
				(font
					(size 1.27 1.27)
				)
			)
		)
		(property "Value" "8K2R2J-3-GP"
			(at 0.064008 -3.993896 180)
			(unlocked yes)
			(layer "F.Fab")
			(hide yes)
			(effects
				(font
					(size 1.016 1.016)
					(thickness 0.1524)
				)
			)
		)
		(property "Device Type" "R402H16"
			(at 0.064008 -5.517896 180)
			(unlocked yes)
			(layer "F.Fab")
			(hide yes)
			(effects
				(font
					(size 1.016 1.016)
					(thickness 0.1524)
				)
			)
		)
		(duplicate_pad_numbers_are_jumpers no)
		(fp_line
			(start 0.508 -0.9398)
			(end -0.508 -0.9398)
			(stroke
				(width 0.1524)
				(type default)
			)
			(layer "F.SilkS")
		)
		(fp_line
			(start -0.508 -0.9398)
			(end -0.508 0.9398)
			(stroke
				(width 0.1524)
				(type default)
			)
			(layer "F.SilkS")
		)
		(fp_rect
			(start -0.508 0.9398)
			(end 0.508 -0.9398)
			(stroke
				(width 0)
				(type default)
			)
			(fill no)
			(layer "F.CrtYd")
		)
		(fp_rect
			(start -0.508 0.9398)
			(end 0.508 -0.9398)
			(stroke
				(width 0)
				(type default)
			)
			(fill no)
			(layer "F.Fab")
		)
		(pad "1" smd custom
			(at 0 -0.4445 180)
			(size 0.1397 0.1397)
			(layers "F.Cu" "F.Mask" "F.Paste")
			(net "EEPROM_WP")
			(options
				(clearance outline)
				(anchor circle)
			)
			(primitives
				(gr_poly
					(pts
						(arc
							(start -0.1778 -0.2794)
							(mid -0.249642 -0.249642)
							(end -0.2794 -0.1778)
						)
						(arc
							(start -0.2794 0.1778)
							(mid -0.249642 0.249642)
							(end -0.1778 0.2794)
						)
						(arc
							(start 0.1778 0.2794)
							(mid 0.249642 0.249642)
							(end 0.2794 0.1778)
						)
						(arc
							(start 0.2794 -0.1778)
							(mid 0.249642 -0.249642)
							(end 0.1778 -0.2794)
						)
					)
					(width 0)
					(fill yes)
				)
			)
		)
		(pad "2" smd custom
			(at 0 0.4445 180)
			(size 0.1397 0.1397)
			(layers "F.Cu" "F.Mask" "F.Paste")
			(net "GND")
			(options
				(clearance outline)
				(anchor circle)
			)
			(primitives
				(gr_poly
					(pts
						(arc
							(start -0.1778 -0.2794)
							(mid -0.249642 -0.249642)
							(end -0.2794 -0.1778)
						)
						(arc
							(start -0.2794 0.1778)
							(mid -0.249642 0.249642)
							(end -0.1778 0.2794)
						)
						(arc
							(start 0.1778 0.2794)
							(mid 0.249642 0.249642)
							(end 0.2794 0.1778)
						)
						(arc
							(start 0.2794 -0.1778)
							(mid 0.249642 -0.249642)
							(end 0.1778 -0.2794)
						)
					)
					(width 0)
					(fill yes)
				)
			)
		)
	)
)
